FILE_TYPE=LIBRARY_PARTS;
TIME=' COMPILATION ON THU JAN 10 16:23:46 1991  ';
primitive '74cbtlv1g125';
  pin
    'B':
      OUTPUT_LOAD='(20.0,-1.0)';
      PIN_NUMBER='(4)';
    'OE_N':
      INPUT_LOAD='(-0.6,0.02)';
      PIN_NUMBER='(1)';
      PIN_GROUP='1';
    'A':
      INPUT_LOAD='(-0.6,0.02)';
      PIN_NUMBER='(2)';
      PIN_GROUP='1';
  end_pin;
  body
BODY_NAME='74cbtlv1g125';
PART_NAME='74cbtlv1g125';
    POWER_PINS='(VCC:5;GND:3)';
  end_body; 
end_primitive;
END.
